(kicad_pcb
	(version 20260206)
	(generator "pcbnew")
	(generator_version "10.0")
	(general
		(thickness 1.6)
		(legacy_teardrops no)
	)
	(paper "A4")
	(title_block
		(title "v1-chassis-manager — T6M_CM_d_v01_1031_1645.brd")
		(comment 1 "Open CloudServer (Microsoft) / footprint 1507 of 2512 (U2), pads 1067-1184 of 1283")
	)
	(layers
		(0 "F.Cu" signal "TOP")
		(4 "In1.Cu" signal "GND1")
		(6 "In2.Cu" signal "IN1")
		(8 "In3.Cu" signal "VCC1")
		(10 "In4.Cu" signal "VCC2")
		(12 "In5.Cu" signal "GND2")
		(14 "In6.Cu" signal "IN2")
		(16 "In7.Cu" signal "IN3")
		(18 "In8.Cu" signal "GND3")
		(2 "B.Cu" signal "BOTTOM")
		(9 "F.Adhes" user "F.Adhesive")
		(11 "B.Adhes" user "B.Adhesive")
		(13 "F.Paste" user "Package Geometry/Pastemask Top")
		(15 "B.Paste" user "Package Geometry/Pastemask Bottom")
		(5 "F.SilkS" user "Ref Des/Silkscreen Top")
		(7 "B.SilkS" user "Ref Des/Silkscreen Bottom")
		(1 "F.Mask" user "Board Geometry/Soldermask Top")
		(3 "B.Mask" user "Board Geometry/Soldermask Bottom")
		(17 "Dwgs.User" user "User.Drawings")
		(19 "Cmts.User" user "User.Comments")
		(21 "Eco1.User" user "User.Eco1")
		(23 "Eco2.User" user "User.Eco2")
		(25 "Edge.Cuts" user "Board Geometry/Outline")
		(27 "Margin" user)
		(31 "F.CrtYd" user "Package Geometry/Place Bound Top")
		(29 "B.CrtYd" user "Package Geometry/Place Bound Bottom")
		(35 "F.Fab" user "Ref Des/Assembly Top")
		(33 "B.Fab" user "Ref Des/Assembly Bottom")
	)
	(footprint ""
		(layer "F.Cu")
		(at 58.000646 -75.799442)
		(property "Reference" "U2"
			(at -20.2438 -18.364708 0)
			(unlocked yes)
			(layer "F.SilkS")
			(effects
				(font
					(size 1.6002 1.1938)
					(thickness 0.1524)
				)
				(justify left)
			)
		)
		(property "Value" ""
			(at 0 0 0)
			(layer "F.Fab")
			(effects
				(font
					(size 1.27 1.27)
				)
			)
		)
		(duplicate_pad_numbers_are_jumpers no)
		(pad "L59" smd circle
			(at 12.582398 -8.41502)
			(size 0.3048 0.3048)
			(layers "F.Cu" "F.Mask" "F.Paste")
			(net "VR_NODE1_VDDR_1V5_CNTL")
		)
		(pad "L60" smd circle
			(at 13.344398 -8.41502)
			(size 0.3048 0.3048)
			(layers "F.Cu" "F.Mask" "F.Paste")
			(net "SPI_CPU_NODE1_WP_R_L")
		)
		(pad "L63" smd circle
			(at 14.794738 -8.440928)
			(size 0.3048 0.3048)
			(layers "F.Cu" "F.Mask" "F.Paste")
			(net "FM_CPLD_NODE1_CPU_RSMRST_L")
		)
		(pad "L65" smd circle
			(at 15.752318 -8.388096)
			(size 0.3048 0.3048)
			(layers "F.Cu" "F.Mask" "F.Paste")
			(net "A_CPU_NODE1_RTC_EXTPAD")
		)
		(pad "M3" smd circle
			(at -15.247112 -7.719314)
			(size 0.3048 0.3048)
			(layers "F.Cu" "F.Mask" "F.Paste")
			(net "GND")
		)
		(pad "M5" smd circle
			(at -14.013688 -7.689088)
			(size 0.3048 0.3048)
			(layers "F.Cu" "F.Mask" "F.Paste")
			(net "GND")
		)
		(pad "M21" smd circle
			(at -6.42874 -7.677404)
			(size 0.3048 0.3048)
			(layers "F.Cu" "F.Mask" "F.Paste")
			(net "GND")
		)
		(pad "M22" smd circle
			(at -5.728716 -7.677404)
			(size 0.3048 0.3048)
			(layers "F.Cu" "F.Mask" "F.Paste")
			(net "GND")
		)
		(pad "M29" smd circle
			(at -2.45618 -7.677404)
			(size 0.3048 0.3048)
			(layers "F.Cu" "F.Mask" "F.Paste")
			(net "GND")
		)
		(pad "M30" smd circle
			(at -1.756156 -7.677404)
			(size 0.3048 0.3048)
			(layers "F.Cu" "F.Mask" "F.Paste")
			(net "GND")
		)
		(pad "M37" smd circle
			(at 1.51638 -7.677404)
			(size 0.3048 0.3048)
			(layers "F.Cu" "F.Mask" "F.Paste")
			(net "P3V3_NODE1")
		)
		(pad "M38" smd circle
			(at 2.216404 -7.677404)
			(size 0.3048 0.3048)
			(layers "F.Cu" "F.Mask" "F.Paste")
			(net "A_CPU_NODE1_HV_GPIO_RCOMP")
		)
		(pad "M44" smd circle
			(at 5.48894 -7.677404)
			(size 0.3048 0.3048)
			(layers "F.Cu" "F.Mask" "F.Paste")
			(net "P3V3_RTC_NODE1")
		)
		(pad "M46" smd circle
			(at 6.188964 -7.677404)
			(size 0.3048 0.3048)
			(layers "F.Cu" "F.Mask" "F.Paste")
			(net "PD_CPU_NODE1_BRD_ID1")
		)
		(pad "M52" smd circle
			(at 9.4615 -7.677404)
			(size 0.3048 0.3048)
			(layers "F.Cu" "F.Mask" "F.Paste")
			(net "TP_CPU_NODE1_M52")
		)
		(pad "M54" smd circle
			(at 10.296398 -7.714996 270)
			(size 0.3048 0.3048)
			(layers "F.Cu" "F.Mask" "F.Paste")
			(net "FM_CPU_NODE1_RSTRDY_L")
		)
		(pad "M56" smd circle
			(at 11.058398 -7.714996)
			(size 0.3048 0.3048)
			(layers "F.Cu" "F.Mask" "F.Paste")
			(net "FM_CPLD_NODE1_PWR_BTN_CPU")
		)
		(pad "M57" smd circle
			(at 11.820398 -7.714996)
			(size 0.3048 0.3048)
			(layers "F.Cu" "F.Mask" "F.Paste")
			(net "GND")
		)
		(pad "M59" smd circle
			(at 12.582398 -7.714996)
			(size 0.3048 0.3048)
			(layers "F.Cu" "F.Mask" "F.Paste")
			(net "Net_298")
		)
		(pad "M60" smd circle
			(at 13.344398 -7.714996)
			(size 0.3048 0.3048)
			(layers "F.Cu" "F.Mask" "F.Paste")
			(net "SMB_BMC_NODE1_HSC_ALERT_L")
		)
		(pad "M62" smd circle
			(at 14.08049 -7.891272)
			(size 0.3048 0.3048)
			(layers "F.Cu" "F.Mask" "F.Paste")
			(net "GND")
		)
		(pad "M64" smd circle
			(at 15.242794 -7.901178)
			(size 0.3048 0.3048)
			(layers "F.Cu" "F.Mask" "F.Paste")
			(net "GND")
		)
		(pad "M66" smd oval
			(at 16.249396 -7.6708 90)
			(size 0.254 0.3429)
			(layers "F.Cu" "F.Mask" "F.Paste")
			(net "GND")
		)
		(pad "N1" smd oval
			(at -16.249396 -7.463536 270)
			(size 0.254 0.3429)
			(layers "F.Cu" "F.Mask" "F.Paste")
			(net "GND")
		)
		(pad "N2" smd circle
			(at -15.640812 -7.114032)
			(size 0.3048 0.3048)
			(layers "F.Cu" "F.Mask" "F.Paste")
			(net "PD_CPU_NODE1_RP2_PERN")
		)
		(pad "N4" smd circle
			(at -14.90091 -7.107936)
			(size 0.3048 0.3048)
			(layers "F.Cu" "F.Mask" "F.Paste")
			(net "PD_CPU_NODE1_RP2_PERP")
		)
		(pad "N5" smd circle
			(at -14.204442 -7.010908)
			(size 0.3048 0.3048)
			(layers "F.Cu" "F.Mask" "F.Paste")
			(net "PD_CPU_NODE1_RP2_PERP")
		)
		(pad "N7" smd circle
			(at -13.344398 -7.47522)
			(size 0.3048 0.3048)
			(layers "F.Cu" "F.Mask" "F.Paste")
			(net "GND")
		)
		(pad "N8" smd circle
			(at -12.582398 -7.47522)
			(size 0.3048 0.3048)
			(layers "F.Cu" "F.Mask" "F.Paste")
			(net "Net_431")
		)
		(pad "N10" smd circle
			(at -11.820398 -7.47522)
			(size 0.3048 0.3048)
			(layers "F.Cu" "F.Mask" "F.Paste")
			(net "Net_428")
		)
		(pad "N11" smd circle
			(at -11.058398 -7.47522)
			(size 0.3048 0.3048)
			(layers "F.Cu" "F.Mask" "F.Paste")
			(net "GND")
		)
		(pad "N13" smd circle
			(at -10.296398 -7.47522)
			(size 0.3048 0.3048)
			(layers "F.Cu" "F.Mask" "F.Paste")
			(net "Net_417")
		)
		(pad "N14" smd circle
			(at -9.534398 -7.47522)
			(size 0.3048 0.3048)
			(layers "F.Cu" "F.Mask" "F.Paste")
			(net "Net_416")
		)
		(pad "N17" smd circle
			(at -8.41502 -7.296404)
			(size 0.3048 0.3048)
			(layers "F.Cu" "F.Mask" "F.Paste")
			(net "Net_422")
		)
		(pad "N18" smd circle
			(at -7.714996 -7.296404)
			(size 0.3048 0.3048)
			(layers "F.Cu" "F.Mask" "F.Paste")
			(net "Net_427")
		)
		(pad "N25" smd circle
			(at -4.44246 -7.296404)
			(size 0.3048 0.3048)
			(layers "F.Cu" "F.Mask" "F.Paste")
			(net "Net_430")
		)
		(pad "N26" smd circle
			(at -3.742436 -7.296404)
			(size 0.3048 0.3048)
			(layers "F.Cu" "F.Mask" "F.Paste")
			(net "Net_426")
		)
		(pad "N32" smd circle
			(at -0.4699 -7.296404)
			(size 0.3048 0.3048)
			(layers "F.Cu" "F.Mask" "F.Paste")
			(net "P1V8_NODE1")
		)
		(pad "N34" smd circle
			(at 0.230124 -7.296404)
			(size 0.3048 0.3048)
			(layers "F.Cu" "F.Mask" "F.Paste")
			(net "GND")
		)
		(pad "N41" smd circle
			(at 3.50266 -7.296404)
			(size 0.3048 0.3048)
			(layers "F.Cu" "F.Mask" "F.Paste")
			(net "P1V8_SUS_NODE1")
		)
		(pad "N42" smd circle
			(at 4.202684 -7.296404)
			(size 0.3048 0.3048)
			(layers "F.Cu" "F.Mask" "F.Paste")
			(net "P3V3_SUS_NODE1")
		)
		(pad "N48" smd circle
			(at 7.47522 -7.296404)
			(size 0.3048 0.3048)
			(layers "F.Cu" "F.Mask" "F.Paste")
			(net "NODE1_BIOS_MB_REV_ID0")
		)
		(pad "N50" smd circle
			(at 8.175244 -7.296404)
			(size 0.3048 0.3048)
			(layers "F.Cu" "F.Mask" "F.Paste")
			(net "Net_296")
		)
		(pad "N62" smd circle
			(at 14.204442 -7.197852)
			(size 0.3048 0.3048)
			(layers "F.Cu" "F.Mask" "F.Paste")
			(net "RST_CPU_NODE1_SRTCRST_L")
		)
		(pad "N63" smd circle
			(at 14.90091 -7.2898)
			(size 0.3048 0.3048)
			(layers "F.Cu" "F.Mask" "F.Paste")
			(net "GND")
		)
		(pad "N65" smd circle
			(at 15.639034 -7.321296)
			(size 0.3048 0.3048)
			(layers "F.Cu" "F.Mask" "F.Paste")
			(net "XTAL_CPU_NODE1_X2PAD")
		)
		(pad "P17" smd circle
			(at -8.41502 -6.534404)
			(size 0.3048 0.3048)
			(layers "F.Cu" "F.Mask" "F.Paste")
			(net "GND")
		)
		(pad "P18" smd circle
			(at -7.714996 -6.534404)
			(size 0.3048 0.3048)
			(layers "F.Cu" "F.Mask" "F.Paste")
			(net "GND")
		)
		(pad "P21" smd circle
			(at -6.42874 -6.915404)
			(size 0.3048 0.3048)
			(layers "F.Cu" "F.Mask" "F.Paste")
			(net "A_SOC_NODE1_THERMDC")
		)
		(pad "P22" smd circle
			(at -5.728716 -6.915404)
			(size 0.3048 0.3048)
			(layers "F.Cu" "F.Mask" "F.Paste")
			(net "TP_CPU_NODE1_SOC_THERMATP1")
		)
		(pad "P25" smd circle
			(at -4.44246 -6.534404)
			(size 0.3048 0.3048)
			(layers "F.Cu" "F.Mask" "F.Paste")
			(net "GND")
		)
		(pad "P26" smd circle
			(at -3.742436 -6.534404)
			(size 0.3048 0.3048)
			(layers "F.Cu" "F.Mask" "F.Paste")
			(net "GND")
		)
		(pad "P29" smd circle
			(at -2.45618 -6.915404)
			(size 0.3048 0.3048)
			(layers "F.Cu" "F.Mask" "F.Paste")
			(net "GND")
		)
		(pad "P30" smd circle
			(at -1.756156 -6.915404)
			(size 0.3048 0.3048)
			(layers "F.Cu" "F.Mask" "F.Paste")
			(net "GND")
		)
		(pad "P32" smd circle
			(at -0.4699 -6.534404)
			(size 0.3048 0.3048)
			(layers "F.Cu" "F.Mask" "F.Paste")
			(net "P1V8_NODE1")
		)
		(pad "P34" smd circle
			(at 0.230124 -6.534404)
			(size 0.3048 0.3048)
			(layers "F.Cu" "F.Mask" "F.Paste")
			(net "A_CPU_NODE1_MV_GPIO_RCOMP")
		)
		(pad "P37" smd circle
			(at 1.51638 -6.915404)
			(size 0.3048 0.3048)
			(layers "F.Cu" "F.Mask" "F.Paste")
			(net "P3V3_NODE1")
		)
		(pad "P38" smd circle
			(at 2.216404 -6.915404)
			(size 0.3048 0.3048)
			(layers "F.Cu" "F.Mask" "F.Paste")
			(net "GND")
		)
		(pad "P41" smd circle
			(at 3.50266 -6.534404)
			(size 0.3048 0.3048)
			(layers "F.Cu" "F.Mask" "F.Paste")
			(net "P1V8_SUS_NODE1")
		)
		(pad "P42" smd circle
			(at 4.202684 -6.534404)
			(size 0.3048 0.3048)
			(layers "F.Cu" "F.Mask" "F.Paste")
			(net "P3V3_SUS_NODE1")
		)
		(pad "P44" smd circle
			(at 5.48894 -6.915404)
			(size 0.3048 0.3048)
			(layers "F.Cu" "F.Mask" "F.Paste")
			(net "P3V3_RTC_NODE1")
		)
		(pad "P46" smd circle
			(at 6.188964 -6.915404)
			(size 0.3048 0.3048)
			(layers "F.Cu" "F.Mask" "F.Paste")
			(net "CLK_14M_CPU_NODE1")
		)
		(pad "P48" smd circle
			(at 7.47522 -6.534404)
			(size 0.3048 0.3048)
			(layers "F.Cu" "F.Mask" "F.Paste")
			(net "P1V05_SUS_NODE1")
		)
		(pad "P50" smd circle
			(at 8.175244 -6.534404)
			(size 0.3048 0.3048)
			(layers "F.Cu" "F.Mask" "F.Paste")
			(net "CONSOLE_SELECT_N")
		)
		(pad "R2" smd circle
			(at -15.639034 -6.18744)
			(size 0.3048 0.3048)
			(layers "F.Cu" "F.Mask" "F.Paste")
			(net "PD_CPU_NODE1_RP2_PERN")
		)
		(pad "R4" smd circle
			(at -14.90091 -6.218936)
			(size 0.3048 0.3048)
			(layers "F.Cu" "F.Mask" "F.Paste")
			(net "PD_CPU_NODE1_RP2_PERP")
		)
		(pad "R5" smd circle
			(at -14.204442 -6.310884)
			(size 0.3048 0.3048)
			(layers "F.Cu" "F.Mask" "F.Paste")
			(net "PD_CPU_NODE1_RP2_PERN")
		)
		(pad "R8" smd circle
			(at -12.963398 -6.188964)
			(size 0.3048 0.3048)
			(layers "F.Cu" "F.Mask" "F.Paste")
			(net "GND")
		)
		(pad "R9" smd circle
			(at -12.201398 -6.188964)
			(size 0.3048 0.3048)
			(layers "F.Cu" "F.Mask" "F.Paste")
			(net "Net_411")
		)
		(pad "R11" smd circle
			(at -11.439398 -6.188964)
			(size 0.3048 0.3048)
			(layers "F.Cu" "F.Mask" "F.Paste")
			(net "Net_409")
		)
		(pad "R12" smd circle
			(at -10.677398 -6.188964)
			(size 0.3048 0.3048)
			(layers "F.Cu" "F.Mask" "F.Paste")
			(net "GND")
		)
		(pad "R14" smd circle
			(at -9.915398 -6.188964)
			(size 0.3048 0.3048)
			(layers "F.Cu" "F.Mask" "F.Paste")
			(net "Net_413")
		)
		(pad "R15" smd circle
			(at -9.153398 -6.188964)
			(size 0.3048 0.3048)
			(layers "F.Cu" "F.Mask" "F.Paste")
			(net "Net_412")
		)
		(pad "R21" smd circle
			(at -6.42874 -6.153404)
			(size 0.3048 0.3048)
			(layers "F.Cu" "F.Mask" "F.Paste")
			(net "A_SOC_NODE1_THERMDA")
		)
		(pad "R22" smd circle
			(at -5.728716 -6.153404)
			(size 0.3048 0.3048)
			(layers "F.Cu" "F.Mask" "F.Paste")
			(net "A_CPU_NODE1_SOC_THERMREFNPAD")
		)
		(pad "R29" smd circle
			(at -2.45618 -6.153404)
			(size 0.3048 0.3048)
			(layers "F.Cu" "F.Mask" "F.Paste")
			(net "GND")
		)
		(pad "R30" smd circle
			(at -1.756156 -6.153404)
			(size 0.3048 0.3048)
			(layers "F.Cu" "F.Mask" "F.Paste")
			(net "GND")
		)
		(pad "R37" smd circle
			(at 1.51638 -6.153404)
			(size 0.3048 0.3048)
			(layers "F.Cu" "F.Mask" "F.Paste")
			(net "P3V3_NODE1")
		)
		(pad "R38" smd circle
			(at 2.216404 -6.153404)
			(size 0.3048 0.3048)
			(layers "F.Cu" "F.Mask" "F.Paste")
			(net "GND")
		)
		(pad "R44" smd circle
			(at 5.48894 -6.153404)
			(size 0.3048 0.3048)
			(layers "F.Cu" "F.Mask" "F.Paste")
			(net "P3V3_RTC_NODE1")
		)
		(pad "R46" smd circle
			(at 6.188964 -6.153404)
			(size 0.3048 0.3048)
			(layers "F.Cu" "F.Mask" "F.Paste")
			(net "GND")
		)
		(pad "R52" smd circle
			(at 9.153398 -6.42874)
			(size 0.3048 0.3048)
			(layers "F.Cu" "F.Mask" "F.Paste")
			(net "GND")
		)
		(pad "R53" smd circle
			(at 9.915398 -6.42874)
			(size 0.3048 0.3048)
			(layers "F.Cu" "F.Mask" "F.Paste")
			(net "GND")
		)
		(pad "R55" smd circle
			(at 10.677398 -6.42874)
			(size 0.3048 0.3048)
			(layers "F.Cu" "F.Mask" "F.Paste")
			(net "GND")
		)
		(pad "R56" smd circle
			(at 11.439398 -6.42874)
			(size 0.3048 0.3048)
			(layers "F.Cu" "F.Mask" "F.Paste")
			(net "FM_CPU_NODE1_SLPMODE")
		)
		(pad "R58" smd circle
			(at 12.201398 -6.42874)
			(size 0.3048 0.3048)
			(layers "F.Cu" "F.Mask" "F.Paste")
			(net "FM_CPU_NODE1_SLPRDY_L")
		)
		(pad "R59" smd circle
			(at 12.963398 -6.42874)
			(size 0.3048 0.3048)
			(layers "F.Cu" "F.Mask" "F.Paste")
			(net "GND")
		)
		(pad "R62" smd circle
			(at 14.204442 -6.497828)
			(size 0.3048 0.3048)
			(layers "F.Cu" "F.Mask" "F.Paste")
			(net "N32265582")
		)
		(pad "R63" smd circle
			(at 14.90091 -6.4008)
			(size 0.3048 0.3048)
			(layers "F.Cu" "F.Mask" "F.Paste")
			(net "LPC_CPU_NODE1_CLK0_DS")
		)
		(pad "R65" smd circle
			(at 15.640812 -6.394704)
			(size 0.3048 0.3048)
			(layers "F.Cu" "F.Mask" "F.Paste")
			(net "XTAL_CPU_NODE1_X1PAD")
		)
		(pad "R66" smd oval
			(at 16.249396 -6.0452 90)
			(size 0.254 0.3429)
			(layers "F.Cu" "F.Mask" "F.Paste")
			(net "GND")
		)
		(pad "T1" smd oval
			(at -16.249396 -5.837936 270)
			(size 0.254 0.3429)
			(layers "F.Cu" "F.Mask" "F.Paste")
			(net "GND")
		)
		(pad "T3" smd circle
			(at -15.242794 -5.607558)
			(size 0.3048 0.3048)
			(layers "F.Cu" "F.Mask" "F.Paste")
			(net "GND")
		)
		(pad "T5" smd circle
			(at -14.08049 -5.617464)
			(size 0.3048 0.3048)
			(layers "F.Cu" "F.Mask" "F.Paste")
			(net "GND")
		)
		(pad "T17" smd circle
			(at -8.41502 -5.772404)
			(size 0.3048 0.3048)
			(layers "F.Cu" "F.Mask" "F.Paste")
			(net "GND")
		)
		(pad "T18" smd circle
			(at -7.714996 -5.772404)
			(size 0.3048 0.3048)
			(layers "F.Cu" "F.Mask" "F.Paste")
			(net "TP_CPU_NODE1_SOC_THERMATP0")
		)
		(pad "T20" smd circle
			(at -6.700774 -5.500624)
			(size 0.3048 0.3048)
			(layers "F.Cu" "F.Mask" "F.Paste")
			(net "GND")
		)
		(pad "T21" smd circle
			(at -6.00075 -5.500624)
			(size 0.3048 0.3048)
			(layers "F.Cu" "F.Mask" "F.Paste")
			(net "GND")
		)
		(pad "T23" smd circle
			(at -5.20065 -5.500624)
			(size 0.3048 0.3048)
			(layers "F.Cu" "F.Mask" "F.Paste")
			(net "GND")
		)
		(pad "T25" smd circle
			(at -4.44246 -5.772404)
			(size 0.3048 0.3048)
			(layers "F.Cu" "F.Mask" "F.Paste")
			(net "GND")
		)
		(pad "T26" smd circle
			(at -3.742436 -5.772404)
			(size 0.3048 0.3048)
			(layers "F.Cu" "F.Mask" "F.Paste")
			(net "GND")
		)
		(pad "T28" smd circle
			(at -2.80035 -5.500624)
			(size 0.3048 0.3048)
			(layers "F.Cu" "F.Mask" "F.Paste")
			(net "GND")
		)
		(pad "T29" smd circle
			(at -2.100326 -5.500624)
			(size 0.3048 0.3048)
			(layers "F.Cu" "F.Mask" "F.Paste")
			(net "GND")
		)
		(pad "T31" smd circle
			(at -1.20015 -5.500624)
			(size 0.3048 0.3048)
			(layers "F.Cu" "F.Mask" "F.Paste")
			(net "GND")
		)
		(pad "T32" smd circle
			(at -0.4699 -5.772404)
			(size 0.3048 0.3048)
			(layers "F.Cu" "F.Mask" "F.Paste")
			(net "P1V8_NODE1")
		)
		(pad "T34" smd circle
			(at 0.230124 -5.772404)
			(size 0.3048 0.3048)
			(layers "F.Cu" "F.Mask" "F.Paste")
			(net "GND")
		)
		(pad "T36" smd circle
			(at 1.20015 -5.500624)
			(size 0.3048 0.3048)
			(layers "F.Cu" "F.Mask" "F.Paste")
			(net "P3V3_NODE1")
		)
		(pad "T37" smd circle
			(at 1.900174 -5.500624)
			(size 0.3048 0.3048)
			(layers "F.Cu" "F.Mask" "F.Paste")
			(net "GND")
		)
		(pad "T39" smd circle
			(at 2.80035 -5.500624)
			(size 0.3048 0.3048)
			(layers "F.Cu" "F.Mask" "F.Paste")
			(net "GND")
		)
		(pad "T41" smd circle
			(at 3.50266 -5.772404)
			(size 0.3048 0.3048)
			(layers "F.Cu" "F.Mask" "F.Paste")
			(net "GND")
		)
		(pad "T42" smd circle
			(at 4.202684 -5.772404)
			(size 0.3048 0.3048)
			(layers "F.Cu" "F.Mask" "F.Paste")
			(net "P3V3_SUS_NODE1")
		)
		(pad "T44" smd circle
			(at 5.20065 -5.500624)
			(size 0.3048 0.3048)
			(layers "F.Cu" "F.Mask" "F.Paste")
			(net "P3V3_RTC_NODE1")
		)
		(pad "T45" smd circle
			(at 5.900674 -5.500624)
			(size 0.3048 0.3048)
			(layers "F.Cu" "F.Mask" "F.Paste")
			(net "GND")
		)
		(pad "T47" smd circle
			(at 6.80085 -5.500624)
			(size 0.3048 0.3048)
			(layers "F.Cu" "F.Mask" "F.Paste")
			(net "P1V05_SUS_NODE1")
		)
		(pad "T48" smd circle
			(at 7.47522 -5.772404)
			(size 0.3048 0.3048)
			(layers "F.Cu" "F.Mask" "F.Paste")
			(net "P1V05_SUS_NODE1")
		)
		(pad "T50" smd circle
			(at 8.175244 -5.772404)
			(size 0.3048 0.3048)
			(layers "F.Cu" "F.Mask" "F.Paste")
			(net "GND")
		)
		(pad "T52" smd circle
			(at 9.153398 -5.728716)
			(size 0.3048 0.3048)
			(layers "F.Cu" "F.Mask" "F.Paste")
			(net "CLK_33K_CPU_NODE1_SUSCLK_RR")
		)
		(pad "T53" smd circle
			(at 9.915398 -5.728716)
			(size 0.3048 0.3048)
			(layers "F.Cu" "F.Mask" "F.Paste")
			(net "FM_CPU_NODE1_RSTWARN")
		)
	)
)
